# BASEBOARD_FAB2 (Tioga Pass) — schematic netlist excerpt (pin names and nets, part order shuffled) for the footprints in the layout excerpt that follows; sources: Cadence DE-HDL packaged netlist, KiCad conversion of Wiwynn_Tioga_Pass_MB.brd

C2U6  CAP  0.22UF 16V 10% X7R  pkg 0402  page 107 : A = P3E_CPU0_PE1_PCH_RXN<1> ; B = P3E_CPU0_PE1_SS_RXN<1>
CR1L3  DIODE  1N4148W IC  pkg SM  page 168 : C = FM_DB_UART_SEL3_N ; A = FM_DB_UART_SEL2_N
C8M6  CAP_A  47UF 4V 20% X5R  pkg 0603V  page 228 : A = PVDDQ_KLM ; B = GND

(kicad_pcb
	(version 20260206)
	(generator "pcbnew")
	(generator_version "10.0")
	(general
		(thickness 1.6)
		(legacy_teardrops no)
	)
	(paper "A4")
	(title_block
		(title "Wiwynn_Tioga_Pass_MB.brd")
		(comment 1 "Tioga Pass / footprints 2772-2774 of 4770")
	)
	(layers
		(0 "F.Cu" signal "TOP")
		(4 "In1.Cu" signal "L2GND")
		(6 "In2.Cu" signal "L3")
		(8 "In3.Cu" signal "L4GND")
		(10 "In4.Cu" signal "L5")
		(12 "In5.Cu" signal "L6GND")
		(14 "In6.Cu" signal "L7VCC")
		(16 "In7.Cu" signal "L8VCC")
		(18 "In8.Cu" signal "L9GND")
		(20 "In9.Cu" signal "L10")
		(22 "In10.Cu" signal "L11GND")
		(24 "In11.Cu" signal "L12")
		(26 "In12.Cu" signal "L13GND")
		(2 "B.Cu" signal "BOTTOM")
		(9 "F.Adhes" user "F.Adhesive")
		(11 "B.Adhes" user "B.Adhesive")
		(13 "F.Paste" user "Package Geometry/Pastemask Top")
		(15 "B.Paste" user "Package Geometry/Pastemask Bottom")
		(5 "F.SilkS" user "Ref Des/Silkscreen Top")
		(7 "B.SilkS" user "Ref Des/Silkscreen Bottom")
		(1 "F.Mask" user "Board Geometry/Soldermask Top")
		(3 "B.Mask" user "Board Geometry/Soldermask Bottom")
		(17 "Dwgs.User" user "User.Drawings")
		(19 "Cmts.User" user "User.Comments")
		(21 "Eco1.User" user "User.Eco1")
		(23 "Eco2.User" user "User.Eco2")
		(25 "Edge.Cuts" user "Board Geometry/Outline")
		(27 "Margin" user)
		(31 "F.CrtYd" user "Package Geometry/Place Bound Top")
		(29 "B.CrtYd" user "Package Geometry/Place Bound Bottom")
		(35 "F.Fab" user "Ref Des/Assembly Top")
		(33 "B.Fab" user "Ref Des/Assembly Bottom")
	)
	(footprint ""
		(layer "B.Cu")
		(at 80.757268 -135.4074 -90)
		(property "Reference" "C8M6"
			(at -1.848866 0.752348 270)
			(unlocked yes)
			(layer "B.SilkS")
			(effects
				(font
					(size 1.27 0.9652)
					(thickness 0.1524)
				)
				(justify mirror)
			)
		)
		(property "Value" ""
			(at 0 0 90)
			(layer "B.Fab")
			(effects
				(font
					(size 1.27 1.27)
				)
				(justify mirror)
			)
		)
		(duplicate_pad_numbers_are_jumpers no)
		(fp_rect
			(start 0.500126 1.598422)
			(end -0.500126 -0.201422)
			(stroke
				(width 0)
				(type default)
			)
			(fill no)
			(layer "B.CrtYd")
		)
		(fp_line
			(start -0.500126 1.598422)
			(end 0.500126 1.598422)
			(stroke
				(width 0.1)
				(type default)
			)
			(layer "B.Fab")
		)
		(fp_line
			(start 0.500126 1.598422)
			(end 0.500126 -0.201422)
			(stroke
				(width 0.1)
				(type default)
			)
			(layer "B.Fab")
		)
		(fp_line
			(start -0.500126 -0.201422)
			(end -0.500126 1.598422)
			(stroke
				(width 0.1)
				(type default)
			)
			(layer "B.Fab")
		)
		(fp_line
			(start 0.500126 -0.201422)
			(end -0.500126 -0.201422)
			(stroke
				(width 0.1)
				(type default)
			)
			(layer "B.Fab")
		)
		(pad "1" smd rect
			(at 0 0 180)
			(size 0.889 0.9906)
			(layers "B.Cu" "B.Mask" "B.Paste")
			(net "PVDDQ_KLM")
		)
		(pad "2" smd rect
			(at 0 1.397 180)
			(size 0.889 0.9906)
			(layers "B.Cu" "B.Mask" "B.Paste")
			(net "GND")
		)
		(zone
			(layer "B.Cu")
			(hatch none 0.5)
			(connect_pads
				(clearance 0)
			)
			(min_thickness 0.25)
			(keepout
				(tracks allowed)
				(vias not_allowed)
				(pads allowed)
				(copperpour not_allowed)
				(footprints allowed)
			)
			(placement
				(enabled no)
				(sheetname "")
			)
			(fill
				(thermal_gap 0.5)
				(thermal_bridge_width 0.5)
				(island_removal_mode 0)
			)
			(polygon
				(pts
					(xy 79.804768 -134.9121) (xy 80.312768 -134.9121) (xy 80.312768 -135.9027) (xy 79.804768 -135.9027)
				)
			)
		)
		(zone
			(layer "B.Cu")
			(hatch none 0.5)
			(connect_pads
				(clearance 0)
			)
			(min_thickness 0.25)
			(keepout
				(tracks not_allowed)
				(vias allowed)
				(pads allowed)
				(copperpour not_allowed)
				(footprints allowed)
			)
			(placement
				(enabled no)
				(sheetname "")
			)
			(fill
				(thermal_gap 0.5)
				(thermal_bridge_width 0.5)
				(island_removal_mode 0)
			)
			(polygon
				(pts
					(xy 79.804768 -134.9121) (xy 80.312768 -134.9121) (xy 80.312768 -135.9027) (xy 79.804768 -135.9027)
				)
			)
		)
	)
	(footprint ""
		(layer "B.Cu")
		(at 484.124 -145.6182 90)
		(property "Reference" "CR1L3"
			(at 0 0 90)
			(layer "B.SilkS")
			(hide yes)
			(effects
				(font
					(size 1.27 1.27)
				)
				(justify mirror)
			)
		)
		(property "Value" ""
			(at 0 0 90)
			(layer "B.Fab")
			(effects
				(font
					(size 1.27 1.27)
				)
				(justify mirror)
			)
		)
		(duplicate_pad_numbers_are_jumpers no)
		(fp_line
			(start 0.9144 0.1016)
			(end 0.9144 2.9464)
			(stroke
				(width 0.1524)
				(type default)
			)
			(layer "B.SilkS")
		)
		(fp_line
			(start 0.8382 0.1016)
			(end 0.9144 0.1016)
			(stroke
				(width 0.1524)
				(type default)
			)
			(layer "B.SilkS")
		)
		(fp_line
			(start -0.8382 0.1016)
			(end -0.9144 0.1016)
			(stroke
				(width 0.1524)
				(type default)
			)
			(layer "B.SilkS")
		)
		(fp_line
			(start -0.9144 0.1016)
			(end -0.9144 2.9464)
			(stroke
				(width 0.1524)
				(type default)
			)
			(layer "B.SilkS")
		)
		(fp_line
			(start 0.9144 2.9464)
			(end 0.8382 2.9464)
			(stroke
				(width 0.1524)
				(type default)
			)
			(layer "B.SilkS")
		)
		(fp_line
			(start -0.9144 2.9464)
			(end -0.8382 2.9464)
			(stroke
				(width 0.1524)
				(type default)
			)
			(layer "B.SilkS")
		)
		(fp_circle
			(center -1.128776 -0.907288)
			(end -1.128776 -0.780288)
			(stroke
				(width 0.254)
				(type default)
			)
			(fill no)
			(layer "B.SilkS")
		)
		(fp_poly
			(pts
				(xy 0 0.1016) (xy -0.5334 0.1016) (xy -0.7366 0.1016) (xy -0.9144 0.1016) (xy -0.9144 2.9464) (xy -0.8382 2.9464)
				(xy -0.762 2.9464) (xy 0.9144 2.9464) (xy 0.9144 2.7686) (xy 0.9144 2.159) (xy 0.9144 0.1016) (xy 0.7366 0.1016)
				(xy 0.5842 0.1016)
			)
			(stroke
				(width 0)
				(type default)
			)
			(fill no)
			(layer "B.CrtYd")
		)
		(fp_line
			(start 0.9144 0.1016)
			(end 0.9144 2.9464)
			(stroke
				(width 0.1)
				(type default)
			)
			(layer "B.Fab")
		)
		(fp_line
			(start -0.9144 0.1016)
			(end 0.9144 0.1016)
			(stroke
				(width 0.1)
				(type default)
			)
			(layer "B.Fab")
		)
		(fp_line
			(start 0.9144 2.9464)
			(end -0.9144 2.9464)
			(stroke
				(width 0.1)
				(type default)
			)
			(layer "B.Fab")
		)
		(fp_line
			(start -0.9144 2.9464)
			(end -0.9144 0.1016)
			(stroke
				(width 0.1)
				(type default)
			)
			(layer "B.Fab")
		)
		(fp_circle
			(center -1.128776 -0.907288)
			(end -1.128776 -0.780288)
			(stroke
				(width 0.254)
				(type default)
			)
			(fill no)
			(layer "B.Fab")
		)
		(pad "1" smd rect
			(at 0 0)
			(size 1.524 0.762)
			(layers "B.Cu" "B.Mask" "B.Paste")
			(net "FM_DB_UART_SEL3_N")
		)
		(pad "2" smd rect
			(at 0 3.048 180)
			(size 1.524 0.762)
			(layers "B.Cu" "B.Mask" "B.Paste")
			(net "FM_DB_UART_SEL2_N")
		)
	)
	(footprint ""
		(layer "B.Cu")
		(at 337.537806 -61.257434)
		(property "Reference" "C2U6"
			(at 0 0 0)
			(layer "B.SilkS")
			(hide yes)
			(effects
				(font
					(size 1.27 1.27)
				)
				(justify mirror)
			)
		)
		(property "Value" ""
			(at 0 0 0)
			(layer "B.Fab")
			(effects
				(font
					(size 1.27 1.27)
				)
				(justify mirror)
			)
		)
		(duplicate_pad_numbers_are_jumpers no)
		(fp_poly
			(pts
				(xy -0.3048 -0.1016) (xy -0.3048 0.9906) (xy 0.3048 0.9906) (xy 0.3048 -0.1016)
			)
			(stroke
				(width 0)
				(type default)
			)
			(fill no)
			(layer "B.CrtYd")
		)
		(fp_line
			(start -0.3048 -0.1016)
			(end 0.3048 -0.1016)
			(stroke
				(width 0.1)
				(type default)
			)
			(layer "B.Fab")
		)
		(fp_line
			(start -0.3048 0.9906)
			(end -0.3048 -0.1016)
			(stroke
				(width 0.1)
				(type default)
			)
			(layer "B.Fab")
		)
		(fp_line
			(start 0.3048 -0.1016)
			(end 0.3048 0.9906)
			(stroke
				(width 0.1)
				(type default)
			)
			(layer "B.Fab")
		)
		(fp_line
			(start 0.3048 0.9906)
			(end -0.3048 0.9906)
			(stroke
				(width 0.1)
				(type default)
			)
			(layer "B.Fab")
		)
		(pad "1" smd rect
			(at 0 0 180)
			(size 0.508 0.508)
			(layers "B.Cu" "B.Mask" "B.Paste")
			(net "P3E_CPU0_PE1_PCH_RXN<1>")
		)
		(pad "2" smd rect
			(at 0 0.889 180)
			(size 0.508 0.508)
			(layers "B.Cu" "B.Mask" "B.Paste")
			(net "P3E_CPU0_PE1_SS_RXN<1>")
		)
		(zone
			(layer "B.Cu")
			(hatch none 0.5)
			(connect_pads
				(clearance 0)
			)
			(min_thickness 0.25)
			(keepout
				(tracks allowed)
				(vias not_allowed)
				(pads allowed)
				(copperpour not_allowed)
				(footprints allowed)
			)
			(placement
				(enabled no)
				(sheetname "")
			)
			(fill
				(thermal_gap 0.5)
				(thermal_bridge_width 0.5)
				(island_removal_mode 0)
			)
			(polygon
				(pts
					(xy 337.791806 -61.003434) (xy 337.283806 -61.003434) (xy 337.283806 -60.622434) (xy 337.791806 -60.622434)
				)
			)
		)
		(zone
			(layer "B.Cu")
			(hatch none 0.5)
			(connect_pads
				(clearance 0)
			)
			(min_thickness 0.25)
			(keepout
				(tracks not_allowed)
				(vias allowed)
				(pads allowed)
				(copperpour not_allowed)
				(footprints allowed)
			)
			(placement
				(enabled no)
				(sheetname "")
			)
			(fill
				(thermal_gap 0.5)
				(thermal_bridge_width 0.5)
				(island_removal_mode 0)
			)
			(polygon
				(pts
					(xy 337.791806 -60.622434) (xy 337.283806 -60.622434) (xy 337.283806 -61.003434) (xy 337.791806 -61.003434)
				)
			)
		)
	)
)
